# T6G (Grand Teton) — schematic netlist excerpt (pin names and nets, part order shuffled) for the footprints in the layout excerpt that follows; sources: Cadence DE-HDL packaged netlist, KiCad conversion of 04192023_DAF0TMB3IC0_F0TG_MB_C_brd_V02_OCP.brd

R1317  Q_RES  4.7K 1% EMPTY  pkg 0402LF  page 357 : A = P3V3_AUX ; B = INA230_8_A1
R4306  Q_RES  0 5% CHIP  pkg 0402LF  page 55 : A = CLK_100M_CPU1_CLK12_R_DN ; B = CLK_100M_CPU1_CLK12_DN

(kicad_pcb
	(version 20260206)
	(generator "pcbnew")
	(generator_version "10.0")
	(general
		(thickness 1.6)
		(legacy_teardrops no)
	)
	(paper "A4")
	(title_block
		(title "04192023_DAF0TMB3IC0_F0TG_MB_C_brd_V02_OCP.brd")
		(comment 1 "Grand Teton / footprints 2275-2277 of 8354")
	)
	(layers
		(0 "F.Cu" signal "TOP")
		(4 "In1.Cu" signal "GND")
		(6 "In2.Cu" signal "IN1")
		(8 "In3.Cu" signal "GND1")
		(10 "In4.Cu" signal "IN2")
		(12 "In5.Cu" signal "GND2")
		(14 "In6.Cu" signal "IN3")
		(16 "In7.Cu" signal "GND3")
		(18 "In8.Cu" signal "VCC")
		(20 "In9.Cu" signal "VCC1")
		(22 "In10.Cu" signal "GND4")
		(24 "In11.Cu" signal "IN4")
		(26 "In12.Cu" signal "GND5")
		(28 "In13.Cu" signal "IN5")
		(30 "In14.Cu" signal "GND6")
		(32 "In15.Cu" signal "IN6")
		(34 "In16.Cu" signal "GND7")
		(2 "B.Cu" signal "BOTTOM")
		(9 "F.Adhes" user "F.Adhesive")
		(11 "B.Adhes" user "B.Adhesive")
		(13 "F.Paste" user "Package Geometry/Pastemask Top")
		(15 "B.Paste" user "Package Geometry/Pastemask Bottom")
		(5 "F.SilkS" user "Ref Des/Silkscreen Top")
		(7 "B.SilkS" user "Ref Des/Silkscreen Bottom")
		(1 "F.Mask" user "Board Geometry/Soldermask Top")
		(3 "B.Mask" user "Board Geometry/Soldermask Bottom")
		(17 "Dwgs.User" user "User.Drawings")
		(19 "Cmts.User" user "User.Comments")
		(21 "Eco1.User" user "User.Eco1")
		(23 "Eco2.User" user "User.Eco2")
		(25 "Edge.Cuts" user "Board Geometry/Outline")
		(27 "Margin" user)
		(31 "F.CrtYd" user "Package Geometry/Place Bound Top")
		(29 "B.CrtYd" user "Package Geometry/Place Bound Bottom")
		(35 "F.Fab" user "Ref Des/Assembly Top")
		(33 "B.Fab" user "Ref Des/Assembly Bottom")
	)
	(footprint ""
		(layer "F.Cu")
		(at 321.107308 -105.44175)
		(property "Reference" "R1317"
			(at 0 0 0)
			(layer "F.SilkS")
			(hide yes)
			(effects
				(font
					(size 1.27 1.27)
				)
			)
		)
		(property "Value" ""
			(at 0 0 0)
			(layer "F.Fab")
			(effects
				(font
					(size 1.27 1.27)
				)
			)
		)
		(duplicate_pad_numbers_are_jumpers no)
		(fp_line
			(start -0.7874 -0.4064)
			(end 0.7874 -0.4064)
			(stroke
				(width 0.1524)
				(type default)
			)
			(layer "F.SilkS")
		)
		(fp_line
			(start -0.7874 0.4064)
			(end -0.7874 -0.4064)
			(stroke
				(width 0.1524)
				(type default)
			)
			(layer "F.SilkS")
		)
		(fp_line
			(start 0.7874 -0.4064)
			(end 0.7874 0.4064)
			(stroke
				(width 0.1524)
				(type default)
			)
			(layer "F.SilkS")
		)
		(fp_line
			(start 0.7874 0.4064)
			(end -0.7874 0.4064)
			(stroke
				(width 0.1524)
				(type default)
			)
			(layer "F.SilkS")
		)
		(fp_line
			(start -0.67945 -0.305054)
			(end -0.12065 -0.305054)
			(stroke
				(width 0.1)
				(type default)
			)
			(layer "F.Fab")
		)
		(fp_line
			(start -0.67945 0.3048)
			(end -0.67945 -0.305054)
			(stroke
				(width 0.1)
				(type default)
			)
			(layer "F.Fab")
		)
		(fp_line
			(start -0.12065 -0.305054)
			(end -0.12065 -0.2794)
			(stroke
				(width 0.1)
				(type default)
			)
			(layer "F.Fab")
		)
		(fp_line
			(start -0.12065 -0.2794)
			(end 0.12065 -0.2794)
			(stroke
				(width 0.1)
				(type default)
			)
			(layer "F.Fab")
		)
		(fp_line
			(start -0.12065 0.2794)
			(end -0.12065 0.3048)
			(stroke
				(width 0.1)
				(type default)
			)
			(layer "F.Fab")
		)
		(fp_line
			(start -0.12065 0.3048)
			(end -0.67945 0.3048)
			(stroke
				(width 0.1)
				(type default)
			)
			(layer "F.Fab")
		)
		(fp_line
			(start 0.120396 0.2794)
			(end -0.12065 0.2794)
			(stroke
				(width 0.1)
				(type default)
			)
			(layer "F.Fab")
		)
		(fp_line
			(start 0.120396 0.3048)
			(end 0.120396 0.2794)
			(stroke
				(width 0.1)
				(type default)
			)
			(layer "F.Fab")
		)
		(fp_line
			(start 0.12065 -0.3048)
			(end 0.67945 -0.3048)
			(stroke
				(width 0.1)
				(type default)
			)
			(layer "F.Fab")
		)
		(fp_line
			(start 0.12065 -0.2794)
			(end 0.12065 -0.3048)
			(stroke
				(width 0.1)
				(type default)
			)
			(layer "F.Fab")
		)
		(fp_line
			(start 0.67945 -0.3048)
			(end 0.67945 0.3048)
			(stroke
				(width 0.1)
				(type default)
			)
			(layer "F.Fab")
		)
		(fp_line
			(start 0.67945 0.3048)
			(end 0.120396 0.3048)
			(stroke
				(width 0.1)
				(type default)
			)
			(layer "F.Fab")
		)
		(pad "1" smd circle
			(at -0.40005 0)
			(size 0 0)
			(layers "F.Cu" "F.Mask" "F.Paste")
			(net "P3V3_AUX")
		)
		(pad "2" smd circle
			(at 0.40005 0)
			(size 0 0)
			(layers "F.Cu" "F.Mask" "F.Paste")
			(net "INA230_8_A1")
		)
	)
	(footprint ""
		(layer "F.Cu")
		(at 234.952286 -257.70713 180)
		(property "Reference" ""
			(at 0 0 180)
			(layer "F.SilkS")
			(hide yes)
			(effects
				(font
					(size 1.27 1.27)
				)
			)
		)
		(property "Value" ""
			(at 0 0 180)
			(layer "F.Fab")
			(effects
				(font
					(size 1.27 1.27)
				)
			)
		)
		(duplicate_pad_numbers_are_jumpers no)
		(pad "1" smd circle
			(at 0 0 180)
			(size 0.9906 0.9906)
			(layers "F.Cu" "F.Mask" "F.Paste")
			(net "Net_49")
		)
		(zone
			(layer "F.Cu")
			(hatch none 0.5)
			(connect_pads
				(clearance 0)
			)
			(min_thickness 0.25)
			(keepout
				(tracks not_allowed)
				(vias allowed)
				(pads allowed)
				(copperpour not_allowed)
				(footprints allowed)
			)
			(placement
				(enabled no)
				(sheetname "")
			)
			(fill
				(thermal_gap 0.5)
				(thermal_bridge_width 0.5)
				(island_removal_mode 0)
			)
			(polygon
				(pts
					(arc
						(start 236.577886 -257.70713)
						(mid 233.326686 -257.70713)
						(end 236.577886 -257.70713)
					)
				)
			)
		)
	)
	(footprint ""
		(layer "F.Cu")
		(at 123.825 -321.655948 90)
		(property "Reference" "R4306"
			(at 0 0 90)
			(layer "F.SilkS")
			(hide yes)
			(effects
				(font
					(size 1.27 1.27)
				)
			)
		)
		(property "Value" ""
			(at 0 0 90)
			(layer "F.Fab")
			(effects
				(font
					(size 1.27 1.27)
				)
			)
		)
		(duplicate_pad_numbers_are_jumpers no)
		(fp_line
			(start -0.422148 -0.4064)
			(end 0.416052 -0.4064)
			(stroke
				(width 0.1524)
				(type default)
			)
			(layer "F.SilkS")
		)
		(fp_line
			(start 0.7874 0.0254)
			(end 0.7874 0.4064)
			(stroke
				(width 0.1524)
				(type default)
			)
			(layer "F.SilkS")
		)
		(fp_line
			(start 0.7874 0.4064)
			(end -0.7874 0.4064)
			(stroke
				(width 0.1524)
				(type default)
			)
			(layer "F.SilkS")
		)
		(fp_line
			(start -0.7874 0.4064)
			(end -0.7874 0.0254)
			(stroke
				(width 0.1524)
				(type default)
			)
			(layer "F.SilkS")
		)
		(fp_line
			(start -0.12065 -0.305054)
			(end -0.12065 -0.2794)
			(stroke
				(width 0.1)
				(type default)
			)
			(layer "F.Fab")
		)
		(fp_line
			(start -0.67945 -0.305054)
			(end -0.12065 -0.305054)
			(stroke
				(width 0.1)
				(type default)
			)
			(layer "F.Fab")
		)
		(fp_line
			(start 0.67945 -0.3048)
			(end 0.67945 0.3048)
			(stroke
				(width 0.1)
				(type default)
			)
			(layer "F.Fab")
		)
		(fp_line
			(start 0.12065 -0.3048)
			(end 0.67945 -0.3048)
			(stroke
				(width 0.1)
				(type default)
			)
			(layer "F.Fab")
		)
		(fp_line
			(start 0.12065 -0.2794)
			(end 0.12065 -0.3048)
			(stroke
				(width 0.1)
				(type default)
			)
			(layer "F.Fab")
		)
		(fp_line
			(start -0.12065 -0.2794)
			(end 0.12065 -0.2794)
			(stroke
				(width 0.1)
				(type default)
			)
			(layer "F.Fab")
		)
		(fp_line
			(start 0.120396 0.2794)
			(end -0.12065 0.2794)
			(stroke
				(width 0.1)
				(type default)
			)
			(layer "F.Fab")
		)
		(fp_line
			(start -0.12065 0.2794)
			(end -0.12065 0.3048)
			(stroke
				(width 0.1)
				(type default)
			)
			(layer "F.Fab")
		)
		(fp_line
			(start 0.67945 0.3048)
			(end 0.120396 0.3048)
			(stroke
				(width 0.1)
				(type default)
			)
			(layer "F.Fab")
		)
		(fp_line
			(start 0.120396 0.3048)
			(end 0.120396 0.2794)
			(stroke
				(width 0.1)
				(type default)
			)
			(layer "F.Fab")
		)
		(fp_line
			(start -0.12065 0.3048)
			(end -0.67945 0.3048)
			(stroke
				(width 0.1)
				(type default)
			)
			(layer "F.Fab")
		)
		(fp_line
			(start -0.67945 0.3048)
			(end -0.67945 -0.305054)
			(stroke
				(width 0.1)
				(type default)
			)
			(layer "F.Fab")
		)
		(pad "1" smd circle
			(at -0.40005 0 90)
			(size 0 0)
			(layers "F.Cu" "F.Mask" "F.Paste")
			(net "CLK_100M_CPU1_CLK12_R_DN")
		)
		(pad "2" smd circle
			(at 0.40005 0 90)
			(size 0 0)
			(layers "F.Cu" "F.Mask" "F.Paste")
			(net "CLK_100M_CPU1_CLK12_DN")
		)
	)
)
